(kicad_pcb
	(version 20260206)
	(generator "pcbnew")
	(generator_version "10.0")
	(general
		(thickness 1.6)
		(legacy_teardrops no)
	)
	(paper "A4")
	(title_block
		(title "03242023_DA0F0TMBIJ0_F0T_Motherboard_J_brd_V01_OCP.brd")
		(comment 1 "Grand Teton / footprints 821-826 of 6105")
	)
	(layers
		(0 "F.Cu" signal "TOP")
		(4 "In1.Cu" signal "GND")
		(6 "In2.Cu" signal "IN1")
		(8 "In3.Cu" signal "GND1")
		(10 "In4.Cu" signal "IN2")
		(12 "In5.Cu" signal "GND2")
		(14 "In6.Cu" signal "IN3")
		(16 "In7.Cu" signal "GND3")
		(18 "In8.Cu" signal "VCC")
		(20 "In9.Cu" signal "VCC1")
		(22 "In10.Cu" signal "GND4")
		(24 "In11.Cu" signal "IN4")
		(26 "In12.Cu" signal "GND5")
		(28 "In13.Cu" signal "IN5")
		(30 "In14.Cu" signal "GND6")
		(32 "In15.Cu" signal "IN6")
		(34 "In16.Cu" signal "GND7")
		(2 "B.Cu" signal "BOTTOM")
		(9 "F.Adhes" user "F.Adhesive")
		(11 "B.Adhes" user "B.Adhesive")
		(13 "F.Paste" user "Package Geometry/Pastemask Top")
		(15 "B.Paste" user "Package Geometry/Pastemask Bottom")
		(5 "F.SilkS" user "Ref Des/Silkscreen Top")
		(7 "B.SilkS" user "Ref Des/Silkscreen Bottom")
		(1 "F.Mask" user "Board Geometry/Soldermask Top")
		(3 "B.Mask" user "Board Geometry/Soldermask Bottom")
		(17 "Dwgs.User" user "User.Drawings")
		(19 "Cmts.User" user "User.Comments")
		(21 "Eco1.User" user "User.Eco1")
		(23 "Eco2.User" user "User.Eco2")
		(25 "Edge.Cuts" user "Board Geometry/Outline")
		(27 "Margin" user)
		(31 "F.CrtYd" user "Package Geometry/Place Bound Top")
		(29 "B.CrtYd" user "Package Geometry/Place Bound Bottom")
		(35 "F.Fab" user "Ref Des/Assembly Top")
		(33 "B.Fab" user "Ref Des/Assembly Bottom")
	)
	(footprint ""
		(layer "F.Cu")
		(at 179.352448 -398.191482 180)
		(property "Reference" "PC2193"
			(at 0 0 180)
			(layer "F.SilkS")
			(hide yes)
			(effects
				(font
					(size 1.27 1.27)
				)
			)
		)
		(property "Value" ""
			(at 0 0 180)
			(layer "F.Fab")
			(effects
				(font
					(size 1.27 1.27)
				)
			)
		)
		(duplicate_pad_numbers_are_jumpers no)
		(fp_line
			(start 0.7874 0.4064)
			(end -0.7874 0.4064)
			(stroke
				(width 0.1524)
				(type default)
			)
			(layer "F.SilkS")
		)
		(fp_line
			(start 0.7874 -0.4064)
			(end 0.7874 0.4064)
			(stroke
				(width 0.1524)
				(type default)
			)
			(layer "F.SilkS")
		)
		(fp_line
			(start -0.7874 0.4064)
			(end -0.7874 -0.4064)
			(stroke
				(width 0.1524)
				(type default)
			)
			(layer "F.SilkS")
		)
		(fp_line
			(start -0.7874 -0.4064)
			(end 0.7874 -0.4064)
			(stroke
				(width 0.1524)
				(type default)
			)
			(layer "F.SilkS")
		)
		(fp_line
			(start 0.67945 0.3048)
			(end 0.120396 0.3048)
			(stroke
				(width 0.1)
				(type default)
			)
			(layer "F.Fab")
		)
		(fp_line
			(start 0.67945 -0.3048)
			(end 0.67945 0.3048)
			(stroke
				(width 0.1)
				(type default)
			)
			(layer "F.Fab")
		)
		(fp_line
			(start 0.12065 -0.2794)
			(end 0.12065 -0.3048)
			(stroke
				(width 0.1)
				(type default)
			)
			(layer "F.Fab")
		)
		(fp_line
			(start 0.12065 -0.3048)
			(end 0.67945 -0.3048)
			(stroke
				(width 0.1)
				(type default)
			)
			(layer "F.Fab")
		)
		(fp_line
			(start 0.120396 0.3048)
			(end 0.120396 0.2794)
			(stroke
				(width 0.1)
				(type default)
			)
			(layer "F.Fab")
		)
		(fp_line
			(start 0.120396 0.2794)
			(end -0.12065 0.2794)
			(stroke
				(width 0.1)
				(type default)
			)
			(layer "F.Fab")
		)
		(fp_line
			(start -0.12065 0.3048)
			(end -0.67945 0.3048)
			(stroke
				(width 0.1)
				(type default)
			)
			(layer "F.Fab")
		)
		(fp_line
			(start -0.12065 0.2794)
			(end -0.12065 0.3048)
			(stroke
				(width 0.1)
				(type default)
			)
			(layer "F.Fab")
		)
		(fp_line
			(start -0.12065 -0.2794)
			(end 0.12065 -0.2794)
			(stroke
				(width 0.1)
				(type default)
			)
			(layer "F.Fab")
		)
		(fp_line
			(start -0.12065 -0.305054)
			(end -0.12065 -0.2794)
			(stroke
				(width 0.1)
				(type default)
			)
			(layer "F.Fab")
		)
		(fp_line
			(start -0.67945 0.3048)
			(end -0.67945 -0.305054)
			(stroke
				(width 0.1)
				(type default)
			)
			(layer "F.Fab")
		)
		(fp_line
			(start -0.67945 -0.305054)
			(end -0.12065 -0.305054)
			(stroke
				(width 0.1)
				(type default)
			)
			(layer "F.Fab")
		)
		(pad "1" smd circle
			(at -0.40005 0 180)
			(size 0 0)
			(layers "F.Cu" "F.Mask" "F.Paste")
			(net "HSC_IMON")
		)
		(pad "2" smd circle
			(at 0.40005 0 180)
			(size 0 0)
			(layers "F.Cu" "F.Mask" "F.Paste")
			(net "AGND_HSC")
		)
	)
	(footprint ""
		(layer "F.Cu")
		(at 416.097974 -175.88865 180)
		(property "Reference" "PC190_P0_2"
			(at 0 0 180)
			(layer "F.SilkS")
			(hide yes)
			(effects
				(font
					(size 1.27 1.27)
				)
			)
		)
		(property "Value" ""
			(at 0 0 180)
			(layer "F.Fab")
			(effects
				(font
					(size 1.27 1.27)
				)
			)
		)
		(duplicate_pad_numbers_are_jumpers no)
		(fp_line
			(start 0.7874 0.4064)
			(end -0.7874 0.4064)
			(stroke
				(width 0.1524)
				(type default)
			)
			(layer "F.SilkS")
		)
		(fp_line
			(start 0.7874 -0.4064)
			(end 0.7874 0.4064)
			(stroke
				(width 0.1524)
				(type default)
			)
			(layer "F.SilkS")
		)
		(fp_line
			(start -0.7874 0.4064)
			(end -0.7874 -0.4064)
			(stroke
				(width 0.1524)
				(type default)
			)
			(layer "F.SilkS")
		)
		(fp_line
			(start -0.7874 -0.4064)
			(end 0.7874 -0.4064)
			(stroke
				(width 0.1524)
				(type default)
			)
			(layer "F.SilkS")
		)
		(fp_line
			(start 0.67945 0.3048)
			(end 0.120396 0.3048)
			(stroke
				(width 0.1)
				(type default)
			)
			(layer "F.Fab")
		)
		(fp_line
			(start 0.67945 -0.3048)
			(end 0.67945 0.3048)
			(stroke
				(width 0.1)
				(type default)
			)
			(layer "F.Fab")
		)
		(fp_line
			(start 0.12065 -0.2794)
			(end 0.12065 -0.3048)
			(stroke
				(width 0.1)
				(type default)
			)
			(layer "F.Fab")
		)
		(fp_line
			(start 0.12065 -0.3048)
			(end 0.67945 -0.3048)
			(stroke
				(width 0.1)
				(type default)
			)
			(layer "F.Fab")
		)
		(fp_line
			(start 0.120396 0.3048)
			(end 0.120396 0.2794)
			(stroke
				(width 0.1)
				(type default)
			)
			(layer "F.Fab")
		)
		(fp_line
			(start 0.120396 0.2794)
			(end -0.12065 0.2794)
			(stroke
				(width 0.1)
				(type default)
			)
			(layer "F.Fab")
		)
		(fp_line
			(start -0.12065 0.3048)
			(end -0.67945 0.3048)
			(stroke
				(width 0.1)
				(type default)
			)
			(layer "F.Fab")
		)
		(fp_line
			(start -0.12065 0.2794)
			(end -0.12065 0.3048)
			(stroke
				(width 0.1)
				(type default)
			)
			(layer "F.Fab")
		)
		(fp_line
			(start -0.12065 -0.2794)
			(end 0.12065 -0.2794)
			(stroke
				(width 0.1)
				(type default)
			)
			(layer "F.Fab")
		)
		(fp_line
			(start -0.12065 -0.305054)
			(end -0.12065 -0.2794)
			(stroke
				(width 0.1)
				(type default)
			)
			(layer "F.Fab")
		)
		(fp_line
			(start -0.67945 0.3048)
			(end -0.67945 -0.305054)
			(stroke
				(width 0.1)
				(type default)
			)
			(layer "F.Fab")
		)
		(fp_line
			(start -0.67945 -0.305054)
			(end -0.12065 -0.305054)
			(stroke
				(width 0.1)
				(type default)
			)
			(layer "F.Fab")
		)
		(pad "1" smd circle
			(at -0.40005 0 180)
			(size 0 0)
			(layers "F.Cu" "F.Mask" "F.Paste")
			(net "SW_P12V_PVCCINFAON_CPU0_FLT")
		)
		(pad "2" smd circle
			(at 0.40005 0 180)
			(size 0 0)
			(layers "F.Cu" "F.Mask" "F.Paste")
			(net "GND")
		)
	)
	(footprint ""
		(layer "F.Cu")
		(at 221.67088 -42.255948)
		(property "Reference" "C1998"
			(at 0 0 0)
			(layer "F.SilkS")
			(hide yes)
			(effects
				(font
					(size 1.27 1.27)
				)
			)
		)
		(property "Value" ""
			(at 0 0 0)
			(layer "F.Fab")
			(effects
				(font
					(size 1.27 1.27)
				)
			)
		)
		(duplicate_pad_numbers_are_jumpers no)
		(fp_line
			(start -0.7874 -0.4064)
			(end 0.7874 -0.4064)
			(stroke
				(width 0.1524)
				(type default)
			)
			(layer "F.SilkS")
		)
		(fp_line
			(start -0.7874 0.4064)
			(end -0.7874 -0.4064)
			(stroke
				(width 0.1524)
				(type default)
			)
			(layer "F.SilkS")
		)
		(fp_line
			(start 0.7874 -0.4064)
			(end 0.7874 0.4064)
			(stroke
				(width 0.1524)
				(type default)
			)
			(layer "F.SilkS")
		)
		(fp_line
			(start 0.7874 0.4064)
			(end -0.7874 0.4064)
			(stroke
				(width 0.1524)
				(type default)
			)
			(layer "F.SilkS")
		)
		(fp_line
			(start -0.67945 -0.305054)
			(end -0.12065 -0.305054)
			(stroke
				(width 0.1)
				(type default)
			)
			(layer "F.Fab")
		)
		(fp_line
			(start -0.67945 0.3048)
			(end -0.67945 -0.305054)
			(stroke
				(width 0.1)
				(type default)
			)
			(layer "F.Fab")
		)
		(fp_line
			(start -0.12065 -0.305054)
			(end -0.12065 -0.2794)
			(stroke
				(width 0.1)
				(type default)
			)
			(layer "F.Fab")
		)
		(fp_line
			(start -0.12065 -0.2794)
			(end 0.12065 -0.2794)
			(stroke
				(width 0.1)
				(type default)
			)
			(layer "F.Fab")
		)
		(fp_line
			(start -0.12065 0.2794)
			(end -0.12065 0.3048)
			(stroke
				(width 0.1)
				(type default)
			)
			(layer "F.Fab")
		)
		(fp_line
			(start -0.12065 0.3048)
			(end -0.67945 0.3048)
			(stroke
				(width 0.1)
				(type default)
			)
			(layer "F.Fab")
		)
		(fp_line
			(start 0.120396 0.2794)
			(end -0.12065 0.2794)
			(stroke
				(width 0.1)
				(type default)
			)
			(layer "F.Fab")
		)
		(fp_line
			(start 0.120396 0.3048)
			(end 0.120396 0.2794)
			(stroke
				(width 0.1)
				(type default)
			)
			(layer "F.Fab")
		)
		(fp_line
			(start 0.12065 -0.3048)
			(end 0.67945 -0.3048)
			(stroke
				(width 0.1)
				(type default)
			)
			(layer "F.Fab")
		)
		(fp_line
			(start 0.12065 -0.2794)
			(end 0.12065 -0.3048)
			(stroke
				(width 0.1)
				(type default)
			)
			(layer "F.Fab")
		)
		(fp_line
			(start 0.67945 -0.3048)
			(end 0.67945 0.3048)
			(stroke
				(width 0.1)
				(type default)
			)
			(layer "F.Fab")
		)
		(fp_line
			(start 0.67945 0.3048)
			(end 0.120396 0.3048)
			(stroke
				(width 0.1)
				(type default)
			)
			(layer "F.Fab")
		)
		(pad "1" smd circle
			(at -0.40005 0)
			(size 0 0)
			(layers "F.Cu" "F.Mask" "F.Paste")
			(net "P3V3_E1S_0")
		)
		(pad "2" smd circle
			(at 0.40005 0)
			(size 0 0)
			(layers "F.Cu" "F.Mask" "F.Paste")
			(net "GND")
		)
	)
	(footprint ""
		(layer "F.Cu")
		(at 9.29513 -98.184208 -90)
		(property "Reference" "C2030"
			(at 0 0 270)
			(layer "F.SilkS")
			(hide yes)
			(effects
				(font
					(size 1.27 1.27)
				)
			)
		)
		(property "Value" ""
			(at 0 0 270)
			(layer "F.Fab")
			(effects
				(font
					(size 1.27 1.27)
				)
			)
		)
		(duplicate_pad_numbers_are_jumpers no)
		(fp_line
			(start -0.7874 0.4064)
			(end -0.7874 -0.4064)
			(stroke
				(width 0.1524)
				(type default)
			)
			(layer "F.SilkS")
		)
		(fp_line
			(start 0.7874 0.4064)
			(end -0.7874 0.4064)
			(stroke
				(width 0.1524)
				(type default)
			)
			(layer "F.SilkS")
		)
		(fp_line
			(start -0.7874 -0.4064)
			(end 0.7874 -0.4064)
			(stroke
				(width 0.1524)
				(type default)
			)
			(layer "F.SilkS")
		)
		(fp_line
			(start 0.7874 -0.4064)
			(end 0.7874 0.4064)
			(stroke
				(width 0.1524)
				(type default)
			)
			(layer "F.SilkS")
		)
		(fp_line
			(start -0.67945 0.3048)
			(end -0.67945 -0.305054)
			(stroke
				(width 0.1)
				(type default)
			)
			(layer "F.Fab")
		)
		(fp_line
			(start -0.12065 0.3048)
			(end -0.67945 0.3048)
			(stroke
				(width 0.1)
				(type default)
			)
			(layer "F.Fab")
		)
		(fp_line
			(start 0.120396 0.3048)
			(end 0.120396 0.2794)
			(stroke
				(width 0.1)
				(type default)
			)
			(layer "F.Fab")
		)
		(fp_line
			(start 0.67945 0.3048)
			(end 0.120396 0.3048)
			(stroke
				(width 0.1)
				(type default)
			)
			(layer "F.Fab")
		)
		(fp_line
			(start -0.12065 0.2794)
			(end -0.12065 0.3048)
			(stroke
				(width 0.1)
				(type default)
			)
			(layer "F.Fab")
		)
		(fp_line
			(start 0.120396 0.2794)
			(end -0.12065 0.2794)
			(stroke
				(width 0.1)
				(type default)
			)
			(layer "F.Fab")
		)
		(fp_line
			(start -0.12065 -0.2794)
			(end 0.12065 -0.2794)
			(stroke
				(width 0.1)
				(type default)
			)
			(layer "F.Fab")
		)
		(fp_line
			(start 0.12065 -0.2794)
			(end 0.12065 -0.3048)
			(stroke
				(width 0.1)
				(type default)
			)
			(layer "F.Fab")
		)
		(fp_line
			(start 0.12065 -0.3048)
			(end 0.67945 -0.3048)
			(stroke
				(width 0.1)
				(type default)
			)
			(layer "F.Fab")
		)
		(fp_line
			(start 0.67945 -0.3048)
			(end 0.67945 0.3048)
			(stroke
				(width 0.1)
				(type default)
			)
			(layer "F.Fab")
		)
		(fp_line
			(start -0.67945 -0.305054)
			(end -0.12065 -0.305054)
			(stroke
				(width 0.1)
				(type default)
			)
			(layer "F.Fab")
		)
		(fp_line
			(start -0.12065 -0.305054)
			(end -0.12065 -0.2794)
			(stroke
				(width 0.1)
				(type default)
			)
			(layer "F.Fab")
		)
		(pad "1" smd circle
			(at -0.40005 0 270)
			(size 0 0)
			(layers "F.Cu" "F.Mask" "F.Paste")
			(net "USB_HUB_XTAL_OUT")
		)
		(pad "2" smd circle
			(at 0.40005 0 270)
			(size 0 0)
			(layers "F.Cu" "F.Mask" "F.Paste")
			(net "GND")
		)
	)
	(footprint ""
		(layer "F.Cu")
		(at 477.30537 -211.009992 90)
		(property "Reference" "X35"
			(at -0.1778 -1.92913 90)
			(unlocked yes)
			(layer "F.SilkS")
			(effects
				(font
					(size 0.7874 0.5842)
					(thickness 0.1524)
				)
				(justify left)
			)
		)
		(property "Value" ""
			(at 0 0 90)
			(layer "F.Fab")
			(effects
				(font
					(size 1.27 1.27)
				)
			)
		)
		(property "Device Type" "TP_TDR_4P_FTS_TH-TP_TDR_4P_DIPA"
			(at 1.30175 1.27 180)
			(unlocked yes)
			(layer "F.Fab")
			(hide yes)
			(effects
				(font
					(size 0.635 0.4064)
					(thickness 0.1524)
				)
			)
		)
		(property "User Part Number" "N_A"
			(at 1.30175 1.27 180)
			(unlocked yes)
			(layer "Cmts.User")
			(hide yes)
			(effects
				(font
					(size 0.635 0.4064)
					(thickness 0.1524)
				)
			)
		)
		(duplicate_pad_numbers_are_jumpers no)
		(fp_line
			(start 2.54 -1.27)
			(end 0 -1.27)
			(stroke
				(width 0.1524)
				(type default)
			)
			(layer "F.SilkS")
		)
		(fp_line
			(start 0 -1.27)
			(end 0 -0.635)
			(stroke
				(width 0.1524)
				(type default)
			)
			(layer "F.SilkS")
		)
		(fp_line
			(start 2.54 -1.1303)
			(end 2.54 -1.27)
			(stroke
				(width 0.1524)
				(type default)
			)
			(layer "F.SilkS")
		)
		(fp_line
			(start 0 0.635)
			(end 0 1.905)
			(stroke
				(width 0.1524)
				(type default)
			)
			(layer "F.SilkS")
		)
		(fp_line
			(start 2.54 1.4097)
			(end 2.54 1.1303)
			(stroke
				(width 0.1524)
				(type default)
			)
			(layer "F.SilkS")
		)
		(fp_line
			(start 0 3.175)
			(end 0 3.81)
			(stroke
				(width 0.1524)
				(type default)
			)
			(layer "F.SilkS")
		)
		(fp_line
			(start 2.54 3.81)
			(end 2.54 3.6703)
			(stroke
				(width 0.1524)
				(type default)
			)
			(layer "F.SilkS")
		)
		(fp_line
			(start 0 3.81)
			(end 2.54 3.81)
			(stroke
				(width 0.1524)
				(type default)
			)
			(layer "F.SilkS")
		)
		(fp_poly
			(pts
				(xy -0.761746 0) (xy -2.285746 -0.762) (xy -2.285746 0.762)
			)
			(stroke
				(width 0)
				(type default)
			)
			(fill yes)
			(layer "F.SilkS")
		)
		(fp_line
			(start 2.54 -1.27)
			(end 0 -1.27)
			(stroke
				(width 0.1)
				(type default)
			)
			(layer "F.Fab")
		)
		(fp_line
			(start 0 -1.27)
			(end 0 3.81)
			(stroke
				(width 0.1)
				(type default)
			)
			(layer "F.Fab")
		)
		(fp_line
			(start 2.54 3.81)
			(end 2.54 -1.27)
			(stroke
				(width 0.1)
				(type default)
			)
			(layer "F.Fab")
		)
		(fp_line
			(start 0 3.81)
			(end 2.54 3.81)
			(stroke
				(width 0.1)
				(type default)
			)
			(layer "F.Fab")
		)
		(fp_poly
			(pts
				(xy -0.761746 0) (xy -2.285746 -0.762) (xy -2.285746 0.762)
			)
			(stroke
				(width 0)
				(type default)
			)
			(fill yes)
			(layer "F.Fab")
		)
		(pad "1" thru_hole circle
			(at 0 0 90)
			(size 1.0033 1.0033)
			(drill 0.249936)
			(layers "*.Cu" "*.Mask")
			(remove_unused_layers no)
			(net "TDR_DIFF_85_NECK_IN2_DP")
			(clearance 0.10795)
			(thermal_gap 0.10795)
			(padstack
				(mode front_inner_back)
				(layer "Inner"
					(shape circle)
					(size 0.8001 0.8001)
					(clearance 0.1524)
				)
				(layer "B.Cu"
					(shape circle)
					(size 1.0033 1.0033)
					(clearance 0.10795)
				)
			)
		)
		(pad "2" thru_hole circle
			(at 2.54 0 90)
			(size 1.9939 1.9939)
			(drill 0.249936)
			(layers "*.Cu" "*.Mask")
			(remove_unused_layers no)
			(net "T1_GND")
			(clearance 0.10795)
			(thermal_gap 0.10795)
			(padstack
				(mode front_inner_back)
				(layer "Inner"
					(shape circle)
					(size 0.8001 0.8001)
					(clearance 0.1524)
				)
				(layer "B.Cu"
					(shape circle)
					(size 1.9939 1.9939)
					(clearance 0.10795)
				)
			)
		)
		(pad "3" thru_hole circle
			(at 2.54 2.54 90)
			(size 1.9939 1.9939)
			(drill 0.249936)
			(layers "*.Cu" "*.Mask")
			(remove_unused_layers no)
			(net "T1_GND")
			(clearance 0.10795)
			(thermal_gap 0.10795)
			(padstack
				(mode front_inner_back)
				(layer "Inner"
					(shape circle)
					(size 0.8001 0.8001)
					(clearance 0.1524)
				)
				(layer "B.Cu"
					(shape circle)
					(size 1.9939 1.9939)
					(clearance 0.10795)
				)
			)
		)
		(pad "4" thru_hole circle
			(at 0 2.54 90)
			(size 1.0033 1.0033)
			(drill 0.249936)
			(layers "*.Cu" "*.Mask")
			(remove_unused_layers no)
			(net "TDR_DIFF_85_NECK_IN2_DN")
			(clearance 0.10795)
			(thermal_gap 0.10795)
			(padstack
				(mode front_inner_back)
				(layer "Inner"
					(shape circle)
					(size 0.8001 0.8001)
					(clearance 0.1524)
				)
				(layer "B.Cu"
					(shape circle)
					(size 1.0033 1.0033)
					(clearance 0.10795)
				)
			)
		)
	)
	(footprint ""
		(layer "F.Cu")
		(at 427.490128 -346.017342)
		(property "Reference" "PC1186"
			(at 0 0 0)
			(layer "F.SilkS")
			(hide yes)
			(effects
				(font
					(size 1.27 1.27)
				)
			)
		)
		(property "Value" ""
			(at 0 0 0)
			(layer "F.Fab")
			(effects
				(font
					(size 1.27 1.27)
				)
			)
		)
		(duplicate_pad_numbers_are_jumpers no)
		(fp_line
			(start 2.750058 0.999998)
			(end -2.750058 0.999998)
			(stroke
				(width 0.1524)
				(type default)
			)
			(layer "F.SilkS")
		)
		(fp_circle
			(center 0 0.999998)
			(end 2.750058 0.999998)
			(stroke
				(width 0.1524)
				(type default)
			)
			(fill no)
			(layer "F.SilkS")
		)
		(fp_poly
			(pts
				(arc
					(start 2.750058 0.999998)
					(mid 0 3.750056)
					(end -2.750058 0.999998)
				)
			)
			(stroke
				(width 0)
				(type default)
			)
			(fill yes)
			(layer "F.SilkS")
		)
		(fp_circle
			(center 0 0.999998)
			(end 2.750058 0.999998)
			(stroke
				(width 0.1)
				(type default)
			)
			(fill no)
			(layer "F.Fab")
		)
		(pad "1" thru_hole rect
			(at 0 0)
			(size 1.5748 1.5748)
			(drill 1.0668)
			(layers "*.Cu" "*.Mask")
			(remove_unused_layers no)
			(net "PVCCFA_EHV_FIVRA_CPU0")
			(clearance 0)
			(padstack
				(mode front_inner_back)
				(layer "Inner"
					(shape circle)
					(size 1.5748 1.5748)
					(clearance 0)
				)
				(layer "B.Cu"
					(shape rect)
					(size 1.5748 1.5748)
					(clearance 0)
				)
			)
		)
		(pad "2" thru_hole circle
			(at 0 1.999996)
			(size 1.5748 1.5748)
			(drill 1.0668)
			(layers "*.Cu" "*.Mask")
			(remove_unused_layers no)
			(net "GND")
			(clearance 0)
		)
	)
)
